# T6G (Grand Teton) — schematic netlist excerpt (pin names and nets, part order shuffled) for the footprints in the layout excerpt that follows; sources: Cadence DE-HDL packaged netlist, KiCad conversion of 04192023_DAF0TMB3IC0_F0TG_MB_C_brd_V02_OCP.brd

C2129  Q_CAP  22UF 4V 20% X6S  pkg C0402  page 68 : A = PVDDCR_SOC_P0 ; B = GND
R3243  Q_RES  2.2K 5% EMPTY  pkg 0402LF  page 151 : A = SMB_OCP_V3_2_3V3AUX_SDA ; B = P3V3_AUX

(kicad_pcb
	(version 20260206)
	(generator "pcbnew")
	(generator_version "10.0")
	(general
		(thickness 1.6)
		(legacy_teardrops no)
	)
	(paper "A4")
	(title_block
		(title "04192023_DAF0TMB3IC0_F0TG_MB_C_brd_V02_OCP.brd")
		(comment 1 "Grand Teton / footprints 5675-5676 of 8354")
	)
	(layers
		(0 "F.Cu" signal "TOP")
		(4 "In1.Cu" signal "GND")
		(6 "In2.Cu" signal "IN1")
		(8 "In3.Cu" signal "GND1")
		(10 "In4.Cu" signal "IN2")
		(12 "In5.Cu" signal "GND2")
		(14 "In6.Cu" signal "IN3")
		(16 "In7.Cu" signal "GND3")
		(18 "In8.Cu" signal "VCC")
		(20 "In9.Cu" signal "VCC1")
		(22 "In10.Cu" signal "GND4")
		(24 "In11.Cu" signal "IN4")
		(26 "In12.Cu" signal "GND5")
		(28 "In13.Cu" signal "IN5")
		(30 "In14.Cu" signal "GND6")
		(32 "In15.Cu" signal "IN6")
		(34 "In16.Cu" signal "GND7")
		(2 "B.Cu" signal "BOTTOM")
		(9 "F.Adhes" user "F.Adhesive")
		(11 "B.Adhes" user "B.Adhesive")
		(13 "F.Paste" user "Package Geometry/Pastemask Top")
		(15 "B.Paste" user "Package Geometry/Pastemask Bottom")
		(5 "F.SilkS" user "Ref Des/Silkscreen Top")
		(7 "B.SilkS" user "Ref Des/Silkscreen Bottom")
		(1 "F.Mask" user "Board Geometry/Soldermask Top")
		(3 "B.Mask" user "Board Geometry/Soldermask Bottom")
		(17 "Dwgs.User" user "User.Drawings")
		(19 "Cmts.User" user "User.Comments")
		(21 "Eco1.User" user "User.Eco1")
		(23 "Eco2.User" user "User.Eco2")
		(25 "Edge.Cuts" user "Board Geometry/Outline")
		(27 "Margin" user)
		(31 "F.CrtYd" user "Package Geometry/Place Bound Top")
		(29 "B.CrtYd" user "Package Geometry/Place Bound Bottom")
		(35 "F.Fab" user "Ref Des/Assembly Top")
		(33 "B.Fab" user "Ref Des/Assembly Bottom")
	)
	(footprint ""
		(layer "B.Cu")
		(at 371.551454 -258.830064)
		(property "Reference" "C2129"
			(at 0 0 0)
			(layer "B.SilkS")
			(hide yes)
			(effects
				(font
					(size 1.27 1.27)
				)
				(justify mirror)
			)
		)
		(property "Value" ""
			(at 0 0 0)
			(layer "B.Fab")
			(effects
				(font
					(size 1.27 1.27)
				)
				(justify mirror)
			)
		)
		(duplicate_pad_numbers_are_jumpers no)
		(fp_line
			(start -0.7874 -0.4064)
			(end -0.7874 0.4064)
			(stroke
				(width 0.1524)
				(type default)
			)
			(layer "B.SilkS")
		)
		(fp_line
			(start -0.7874 0.4064)
			(end 0.7874 0.4064)
			(stroke
				(width 0.1524)
				(type default)
			)
			(layer "B.SilkS")
		)
		(fp_line
			(start 0.7874 -0.4064)
			(end -0.7874 -0.4064)
			(stroke
				(width 0.1524)
				(type default)
			)
			(layer "B.SilkS")
		)
		(fp_line
			(start 0.7874 0.4064)
			(end 0.7874 -0.4064)
			(stroke
				(width 0.1524)
				(type default)
			)
			(layer "B.SilkS")
		)
		(fp_line
			(start -0.67945 -0.3048)
			(end -0.67945 0.3048)
			(stroke
				(width 0.1)
				(type default)
			)
			(layer "B.Fab")
		)
		(fp_line
			(start -0.67945 0.3048)
			(end -0.120396 0.3048)
			(stroke
				(width 0.1)
				(type default)
			)
			(layer "B.Fab")
		)
		(fp_line
			(start -0.12065 -0.3048)
			(end -0.67945 -0.3048)
			(stroke
				(width 0.1)
				(type default)
			)
			(layer "B.Fab")
		)
		(fp_line
			(start -0.12065 -0.2794)
			(end -0.12065 -0.3048)
			(stroke
				(width 0.1)
				(type default)
			)
			(layer "B.Fab")
		)
		(fp_line
			(start -0.120396 0.2794)
			(end 0.12065 0.2794)
			(stroke
				(width 0.1)
				(type default)
			)
			(layer "B.Fab")
		)
		(fp_line
			(start -0.120396 0.3048)
			(end -0.120396 0.2794)
			(stroke
				(width 0.1)
				(type default)
			)
			(layer "B.Fab")
		)
		(fp_line
			(start 0.12065 -0.305054)
			(end 0.12065 -0.2794)
			(stroke
				(width 0.1)
				(type default)
			)
			(layer "B.Fab")
		)
		(fp_line
			(start 0.12065 -0.2794)
			(end -0.12065 -0.2794)
			(stroke
				(width 0.1)
				(type default)
			)
			(layer "B.Fab")
		)
		(fp_line
			(start 0.12065 0.2794)
			(end 0.12065 0.3048)
			(stroke
				(width 0.1)
				(type default)
			)
			(layer "B.Fab")
		)
		(fp_line
			(start 0.12065 0.3048)
			(end 0.67945 0.3048)
			(stroke
				(width 0.1)
				(type default)
			)
			(layer "B.Fab")
		)
		(fp_line
			(start 0.67945 -0.305054)
			(end 0.12065 -0.305054)
			(stroke
				(width 0.1)
				(type default)
			)
			(layer "B.Fab")
		)
		(fp_line
			(start 0.67945 0.3048)
			(end 0.67945 -0.305054)
			(stroke
				(width 0.1)
				(type default)
			)
			(layer "B.Fab")
		)
		(pad "1" smd circle
			(at 0.40005 0 180)
			(size 0 0)
			(layers "B.Cu" "B.Mask" "B.Paste")
			(net "PVDDCR_SOC_P0")
		)
		(pad "2" smd circle
			(at -0.40005 0 180)
			(size 0 0)
			(layers "B.Cu" "B.Mask" "B.Paste")
			(net "GND")
		)
	)
	(footprint ""
		(layer "B.Cu")
		(at 171.440602 -8.062468 -90)
		(property "Reference" "R3243"
			(at 0 0 90)
			(layer "B.SilkS")
			(hide yes)
			(effects
				(font
					(size 1.27 1.27)
				)
				(justify mirror)
			)
		)
		(property "Value" ""
			(at 0 0 90)
			(layer "B.Fab")
			(effects
				(font
					(size 1.27 1.27)
				)
				(justify mirror)
			)
		)
		(duplicate_pad_numbers_are_jumpers no)
		(fp_line
			(start -0.7874 0.4064)
			(end 0.7874 0.4064)
			(stroke
				(width 0.1524)
				(type default)
			)
			(layer "B.SilkS")
		)
		(fp_line
			(start 0.7874 0.4064)
			(end 0.7874 -0.4064)
			(stroke
				(width 0.1524)
				(type default)
			)
			(layer "B.SilkS")
		)
		(fp_line
			(start -0.7874 -0.4064)
			(end -0.7874 0.4064)
			(stroke
				(width 0.1524)
				(type default)
			)
			(layer "B.SilkS")
		)
		(fp_line
			(start 0.7874 -0.4064)
			(end -0.7874 -0.4064)
			(stroke
				(width 0.1524)
				(type default)
			)
			(layer "B.SilkS")
		)
		(fp_line
			(start -0.67945 0.3048)
			(end -0.120396 0.3048)
			(stroke
				(width 0.1)
				(type default)
			)
			(layer "B.Fab")
		)
		(fp_line
			(start -0.120396 0.3048)
			(end -0.120396 0.2794)
			(stroke
				(width 0.1)
				(type default)
			)
			(layer "B.Fab")
		)
		(fp_line
			(start 0.12065 0.3048)
			(end 0.67945 0.3048)
			(stroke
				(width 0.1)
				(type default)
			)
			(layer "B.Fab")
		)
		(fp_line
			(start 0.67945 0.3048)
			(end 0.67945 -0.305054)
			(stroke
				(width 0.1)
				(type default)
			)
			(layer "B.Fab")
		)
		(fp_line
			(start -0.120396 0.2794)
			(end 0.12065 0.2794)
			(stroke
				(width 0.1)
				(type default)
			)
			(layer "B.Fab")
		)
		(fp_line
			(start 0.12065 0.2794)
			(end 0.12065 0.3048)
			(stroke
				(width 0.1)
				(type default)
			)
			(layer "B.Fab")
		)
		(fp_line
			(start -0.12065 -0.2794)
			(end -0.12065 -0.3048)
			(stroke
				(width 0.1)
				(type default)
			)
			(layer "B.Fab")
		)
		(fp_line
			(start 0.12065 -0.2794)
			(end -0.12065 -0.2794)
			(stroke
				(width 0.1)
				(type default)
			)
			(layer "B.Fab")
		)
		(fp_line
			(start -0.67945 -0.3048)
			(end -0.67945 0.3048)
			(stroke
				(width 0.1)
				(type default)
			)
			(layer "B.Fab")
		)
		(fp_line
			(start -0.12065 -0.3048)
			(end -0.67945 -0.3048)
			(stroke
				(width 0.1)
				(type default)
			)
			(layer "B.Fab")
		)
		(fp_line
			(start 0.12065 -0.305054)
			(end 0.12065 -0.2794)
			(stroke
				(width 0.1)
				(type default)
			)
			(layer "B.Fab")
		)
		(fp_line
			(start 0.67945 -0.305054)
			(end 0.12065 -0.305054)
			(stroke
				(width 0.1)
				(type default)
			)
			(layer "B.Fab")
		)
		(pad "1" smd circle
			(at 0.40005 0 90)
			(size 0 0)
			(layers "B.Cu" "B.Mask" "B.Paste")
			(net "SMB_OCP_V3_2_3V3AUX_SDA")
		)
		(pad "2" smd circle
			(at -0.40005 0 90)
			(size 0 0)
			(layers "B.Cu" "B.Mask" "B.Paste")
			(net "P3V3_AUX")
		)
	)
)
